FILE_TYPE=LIBRARY_PARTS;
primitive 'Q_INDUCTOR4P_14';
  pin
    '2':
      PIN_NUMBER='(2)';
      BIDIRECTIONAL='TRUE';
      INPUT_LOAD='(-0.01,0.01)';
      OUTPUT_LOAD='(1.0,-1.0)';
    '3':
      PIN_NUMBER='(3)';
      BIDIRECTIONAL='TRUE';
      INPUT_LOAD='(-0.01,0.01)';
      OUTPUT_LOAD='(1.0,-1.0)';
    '4':
      PIN_NUMBER='(4)';
      BIDIRECTIONAL='TRUE';
      INPUT_LOAD='(-0.01,0.01)';
      OUTPUT_LOAD='(1.0,-1.0)';
    '1':
      PIN_NUMBER='(1)';
      BIDIRECTIONAL='TRUE';
      INPUT_LOAD='(-0.01,0.01)';
      OUTPUT_LOAD='(1.0,-1.0)';
  end_pin;
  body
    PART_NAME='Q_INDUCTOR4P_14';
    BODY_NAME='Q_INDUCTOR4P_14';
    PHYS_DES_PREFIX='L';
    CLASS='DISCRETE';
  end_body;
end_primitive;

END.
